(kicad_pcb
	(version 20260206)
	(generator "pcbnew")
	(generator_version "10.0")
	(general
		(thickness 1.6)
		(legacy_teardrops no)
	)
	(paper "A4")
	(title_block
		(title "03242023_DA0F0TMBIJ0_F0T_Motherboard_J_brd_V01_OCP.brd")
		(comment 1 "Grand Teton / footprints 4913-4918 of 6105")
	)
	(layers
		(0 "F.Cu" signal "TOP")
		(4 "In1.Cu" signal "GND")
		(6 "In2.Cu" signal "IN1")
		(8 "In3.Cu" signal "GND1")
		(10 "In4.Cu" signal "IN2")
		(12 "In5.Cu" signal "GND2")
		(14 "In6.Cu" signal "IN3")
		(16 "In7.Cu" signal "GND3")
		(18 "In8.Cu" signal "VCC")
		(20 "In9.Cu" signal "VCC1")
		(22 "In10.Cu" signal "GND4")
		(24 "In11.Cu" signal "IN4")
		(26 "In12.Cu" signal "GND5")
		(28 "In13.Cu" signal "IN5")
		(30 "In14.Cu" signal "GND6")
		(32 "In15.Cu" signal "IN6")
		(34 "In16.Cu" signal "GND7")
		(2 "B.Cu" signal "BOTTOM")
		(9 "F.Adhes" user "F.Adhesive")
		(11 "B.Adhes" user "B.Adhesive")
		(13 "F.Paste" user "Package Geometry/Pastemask Top")
		(15 "B.Paste" user "Package Geometry/Pastemask Bottom")
		(5 "F.SilkS" user "Ref Des/Silkscreen Top")
		(7 "B.SilkS" user "Ref Des/Silkscreen Bottom")
		(1 "F.Mask" user "Board Geometry/Soldermask Top")
		(3 "B.Mask" user "Board Geometry/Soldermask Bottom")
		(17 "Dwgs.User" user "User.Drawings")
		(19 "Cmts.User" user "User.Comments")
		(21 "Eco1.User" user "User.Eco1")
		(23 "Eco2.User" user "User.Eco2")
		(25 "Edge.Cuts" user "Board Geometry/Outline")
		(27 "Margin" user)
		(31 "F.CrtYd" user "Package Geometry/Place Bound Top")
		(29 "B.CrtYd" user "Package Geometry/Place Bound Bottom")
		(35 "F.Fab" user "Ref Des/Assembly Top")
		(33 "B.Fab" user "Ref Des/Assembly Bottom")
	)
	(footprint ""
		(layer "B.Cu")
		(at 212.725 -57.061608 90)
		(property "Reference" "R4093"
			(at 0 0 90)
			(layer "B.SilkS")
			(hide yes)
			(effects
				(font
					(size 1.27 1.27)
				)
				(justify mirror)
			)
		)
		(property "Value" ""
			(at 0 0 90)
			(layer "B.Fab")
			(effects
				(font
					(size 1.27 1.27)
				)
				(justify mirror)
			)
		)
		(duplicate_pad_numbers_are_jumpers no)
		(fp_line
			(start 0.7874 -0.4064)
			(end -0.7874 -0.4064)
			(stroke
				(width 0.1524)
				(type default)
			)
			(layer "B.SilkS")
		)
		(fp_line
			(start -0.7874 -0.4064)
			(end -0.7874 0.4064)
			(stroke
				(width 0.1524)
				(type default)
			)
			(layer "B.SilkS")
		)
		(fp_line
			(start 0.7874 0.4064)
			(end 0.7874 -0.4064)
			(stroke
				(width 0.1524)
				(type default)
			)
			(layer "B.SilkS")
		)
		(fp_line
			(start -0.7874 0.4064)
			(end 0.7874 0.4064)
			(stroke
				(width 0.1524)
				(type default)
			)
			(layer "B.SilkS")
		)
		(fp_line
			(start 0.67945 -0.305054)
			(end 0.12065 -0.305054)
			(stroke
				(width 0.1)
				(type default)
			)
			(layer "B.Fab")
		)
		(fp_line
			(start 0.12065 -0.305054)
			(end 0.12065 -0.2794)
			(stroke
				(width 0.1)
				(type default)
			)
			(layer "B.Fab")
		)
		(fp_line
			(start -0.12065 -0.3048)
			(end -0.67945 -0.3048)
			(stroke
				(width 0.1)
				(type default)
			)
			(layer "B.Fab")
		)
		(fp_line
			(start -0.67945 -0.3048)
			(end -0.67945 0.3048)
			(stroke
				(width 0.1)
				(type default)
			)
			(layer "B.Fab")
		)
		(fp_line
			(start 0.12065 -0.2794)
			(end -0.12065 -0.2794)
			(stroke
				(width 0.1)
				(type default)
			)
			(layer "B.Fab")
		)
		(fp_line
			(start -0.12065 -0.2794)
			(end -0.12065 -0.3048)
			(stroke
				(width 0.1)
				(type default)
			)
			(layer "B.Fab")
		)
		(fp_line
			(start 0.12065 0.2794)
			(end 0.12065 0.3048)
			(stroke
				(width 0.1)
				(type default)
			)
			(layer "B.Fab")
		)
		(fp_line
			(start -0.120396 0.2794)
			(end 0.12065 0.2794)
			(stroke
				(width 0.1)
				(type default)
			)
			(layer "B.Fab")
		)
		(fp_line
			(start 0.67945 0.3048)
			(end 0.67945 -0.305054)
			(stroke
				(width 0.1)
				(type default)
			)
			(layer "B.Fab")
		)
		(fp_line
			(start 0.12065 0.3048)
			(end 0.67945 0.3048)
			(stroke
				(width 0.1)
				(type default)
			)
			(layer "B.Fab")
		)
		(fp_line
			(start -0.120396 0.3048)
			(end -0.120396 0.2794)
			(stroke
				(width 0.1)
				(type default)
			)
			(layer "B.Fab")
		)
		(fp_line
			(start -0.67945 0.3048)
			(end -0.120396 0.3048)
			(stroke
				(width 0.1)
				(type default)
			)
			(layer "B.Fab")
		)
		(pad "1" smd circle
			(at 0.40005 0 270)
			(size 0 0)
			(layers "B.Cu" "B.Mask" "B.Paste")
			(net "P3V3_AUX")
		)
		(pad "2" smd circle
			(at -0.40005 0 270)
			(size 0 0)
			(layers "B.Cu" "B.Mask" "B.Paste")
			(net "E1S_0_P3V3_ADC_ALERT_R")
		)
	)
	(footprint ""
		(layer "B.Cu")
		(at 305.624738 -153.82367 180)
		(property "Reference" "R693"
			(at 0 0 0)
			(layer "B.SilkS")
			(hide yes)
			(effects
				(font
					(size 1.27 1.27)
				)
				(justify mirror)
			)
		)
		(property "Value" ""
			(at 0 0 0)
			(layer "B.Fab")
			(effects
				(font
					(size 1.27 1.27)
				)
				(justify mirror)
			)
		)
		(duplicate_pad_numbers_are_jumpers no)
		(fp_line
			(start 0.7874 0.4064)
			(end 0.7874 -0.4064)
			(stroke
				(width 0.1524)
				(type default)
			)
			(layer "B.SilkS")
		)
		(fp_line
			(start 0.7874 -0.4064)
			(end -0.7874 -0.4064)
			(stroke
				(width 0.1524)
				(type default)
			)
			(layer "B.SilkS")
		)
		(fp_line
			(start -0.7874 0.4064)
			(end 0.7874 0.4064)
			(stroke
				(width 0.1524)
				(type default)
			)
			(layer "B.SilkS")
		)
		(fp_line
			(start -0.7874 -0.4064)
			(end -0.7874 0.4064)
			(stroke
				(width 0.1524)
				(type default)
			)
			(layer "B.SilkS")
		)
		(fp_line
			(start 0.67945 0.3048)
			(end 0.67945 -0.305054)
			(stroke
				(width 0.1)
				(type default)
			)
			(layer "B.Fab")
		)
		(fp_line
			(start 0.67945 -0.305054)
			(end 0.12065 -0.305054)
			(stroke
				(width 0.1)
				(type default)
			)
			(layer "B.Fab")
		)
		(fp_line
			(start 0.12065 0.3048)
			(end 0.67945 0.3048)
			(stroke
				(width 0.1)
				(type default)
			)
			(layer "B.Fab")
		)
		(fp_line
			(start 0.12065 0.2794)
			(end 0.12065 0.3048)
			(stroke
				(width 0.1)
				(type default)
			)
			(layer "B.Fab")
		)
		(fp_line
			(start 0.12065 -0.2794)
			(end -0.12065 -0.2794)
			(stroke
				(width 0.1)
				(type default)
			)
			(layer "B.Fab")
		)
		(fp_line
			(start 0.12065 -0.305054)
			(end 0.12065 -0.2794)
			(stroke
				(width 0.1)
				(type default)
			)
			(layer "B.Fab")
		)
		(fp_line
			(start -0.120396 0.3048)
			(end -0.120396 0.2794)
			(stroke
				(width 0.1)
				(type default)
			)
			(layer "B.Fab")
		)
		(fp_line
			(start -0.120396 0.2794)
			(end 0.12065 0.2794)
			(stroke
				(width 0.1)
				(type default)
			)
			(layer "B.Fab")
		)
		(fp_line
			(start -0.12065 -0.2794)
			(end -0.12065 -0.3048)
			(stroke
				(width 0.1)
				(type default)
			)
			(layer "B.Fab")
		)
		(fp_line
			(start -0.12065 -0.3048)
			(end -0.67945 -0.3048)
			(stroke
				(width 0.1)
				(type default)
			)
			(layer "B.Fab")
		)
		(fp_line
			(start -0.67945 0.3048)
			(end -0.120396 0.3048)
			(stroke
				(width 0.1)
				(type default)
			)
			(layer "B.Fab")
		)
		(fp_line
			(start -0.67945 -0.3048)
			(end -0.67945 0.3048)
			(stroke
				(width 0.1)
				(type default)
			)
			(layer "B.Fab")
		)
		(pad "1" smd circle
			(at 0.40005 0)
			(size 0 0)
			(layers "B.Cu" "B.Mask" "B.Paste")
			(net "I3C_SPD_DDREFGH_CPU0_LVC1_R_SCL")
		)
		(pad "2" smd circle
			(at -0.40005 0)
			(size 0 0)
			(layers "B.Cu" "B.Mask" "B.Paste")
			(net "I3C_SPD_DDREFGH_CPU0_LVC1_SCL")
		)
	)
	(footprint ""
		(layer "B.Cu")
		(at 344.754708 -62.056264 90)
		(property "Reference" "C161"
			(at 0 0 90)
			(layer "B.SilkS")
			(hide yes)
			(effects
				(font
					(size 1.27 1.27)
				)
				(justify mirror)
			)
		)
		(property "Value" ""
			(at 0 0 90)
			(layer "B.Fab")
			(effects
				(font
					(size 1.27 1.27)
				)
				(justify mirror)
			)
		)
		(duplicate_pad_numbers_are_jumpers no)
		(fp_line
			(start 0.299974 -0.150114)
			(end -0.299974 -0.150114)
			(stroke
				(width 0.1)
				(type default)
			)
			(layer "B.Fab")
		)
		(fp_line
			(start -0.299974 -0.150114)
			(end -0.299974 0.150114)
			(stroke
				(width 0.1)
				(type default)
			)
			(layer "B.Fab")
		)
		(fp_line
			(start 0.299974 0.150114)
			(end 0.299974 -0.150114)
			(stroke
				(width 0.1)
				(type default)
			)
			(layer "B.Fab")
		)
		(fp_line
			(start -0.299974 0.150114)
			(end 0.299974 0.150114)
			(stroke
				(width 0.1)
				(type default)
			)
			(layer "B.Fab")
		)
		(pad "1" smd rect
			(at 0.2667 0 270)
			(size 0.3048 0.381)
			(layers "B.Cu" "B.Mask" "B.Paste")
			(net "DMI_CPU0_PCH_RX_C_DN<4>")
		)
		(pad "2" smd rect
			(at -0.2667 0 270)
			(size 0.3048 0.381)
			(layers "B.Cu" "B.Mask" "B.Paste")
			(net "DMI_CPU0_PCH_RX_DN<4>")
		)
	)
	(footprint ""
		(layer "B.Cu")
		(at 10.373106 -195.816728 -90)
		(property "Reference" "C562"
			(at 0 0 90)
			(layer "B.SilkS")
			(hide yes)
			(effects
				(font
					(size 1.27 1.27)
				)
				(justify mirror)
			)
		)
		(property "Value" ""
			(at 0 0 90)
			(layer "B.Fab")
			(effects
				(font
					(size 1.27 1.27)
				)
				(justify mirror)
			)
		)
		(duplicate_pad_numbers_are_jumpers no)
		(fp_line
			(start -0.7874 0.4064)
			(end 0.7874 0.4064)
			(stroke
				(width 0.1524)
				(type default)
			)
			(layer "B.SilkS")
		)
		(fp_line
			(start 0.7874 0.4064)
			(end 0.7874 -0.4064)
			(stroke
				(width 0.1524)
				(type default)
			)
			(layer "B.SilkS")
		)
		(fp_line
			(start -0.7874 -0.4064)
			(end -0.7874 0.4064)
			(stroke
				(width 0.1524)
				(type default)
			)
			(layer "B.SilkS")
		)
		(fp_line
			(start 0.7874 -0.4064)
			(end -0.7874 -0.4064)
			(stroke
				(width 0.1524)
				(type default)
			)
			(layer "B.SilkS")
		)
		(fp_line
			(start -0.67945 0.3048)
			(end -0.120396 0.3048)
			(stroke
				(width 0.1)
				(type default)
			)
			(layer "B.Fab")
		)
		(fp_line
			(start -0.120396 0.3048)
			(end -0.120396 0.2794)
			(stroke
				(width 0.1)
				(type default)
			)
			(layer "B.Fab")
		)
		(fp_line
			(start 0.12065 0.3048)
			(end 0.67945 0.3048)
			(stroke
				(width 0.1)
				(type default)
			)
			(layer "B.Fab")
		)
		(fp_line
			(start 0.67945 0.3048)
			(end 0.67945 -0.305054)
			(stroke
				(width 0.1)
				(type default)
			)
			(layer "B.Fab")
		)
		(fp_line
			(start -0.120396 0.2794)
			(end 0.12065 0.2794)
			(stroke
				(width 0.1)
				(type default)
			)
			(layer "B.Fab")
		)
		(fp_line
			(start 0.12065 0.2794)
			(end 0.12065 0.3048)
			(stroke
				(width 0.1)
				(type default)
			)
			(layer "B.Fab")
		)
		(fp_line
			(start -0.12065 -0.2794)
			(end -0.12065 -0.3048)
			(stroke
				(width 0.1)
				(type default)
			)
			(layer "B.Fab")
		)
		(fp_line
			(start 0.12065 -0.2794)
			(end -0.12065 -0.2794)
			(stroke
				(width 0.1)
				(type default)
			)
			(layer "B.Fab")
		)
		(fp_line
			(start -0.67945 -0.3048)
			(end -0.67945 0.3048)
			(stroke
				(width 0.1)
				(type default)
			)
			(layer "B.Fab")
		)
		(fp_line
			(start -0.12065 -0.3048)
			(end -0.67945 -0.3048)
			(stroke
				(width 0.1)
				(type default)
			)
			(layer "B.Fab")
		)
		(fp_line
			(start 0.12065 -0.305054)
			(end 0.12065 -0.2794)
			(stroke
				(width 0.1)
				(type default)
			)
			(layer "B.Fab")
		)
		(fp_line
			(start 0.67945 -0.305054)
			(end 0.12065 -0.305054)
			(stroke
				(width 0.1)
				(type default)
			)
			(layer "B.Fab")
		)
		(pad "1" smd circle
			(at 0.40005 0 90)
			(size 0 0)
			(layers "B.Cu" "B.Mask" "B.Paste")
			(net "P3V3_AUX")
		)
		(pad "2" smd circle
			(at -0.40005 0 90)
			(size 0 0)
			(layers "B.Cu" "B.Mask" "B.Paste")
			(net "GND")
		)
	)
	(footprint ""
		(layer "B.Cu")
		(at 215.206834 -318.826642 90)
		(property "Reference" "R907"
			(at 0 0 90)
			(layer "B.SilkS")
			(hide yes)
			(effects
				(font
					(size 1.27 1.27)
				)
				(justify mirror)
			)
		)
		(property "Value" ""
			(at 0 0 90)
			(layer "B.Fab")
			(effects
				(font
					(size 1.27 1.27)
				)
				(justify mirror)
			)
		)
		(duplicate_pad_numbers_are_jumpers no)
		(fp_line
			(start 0.7874 -0.4064)
			(end -0.7874 -0.4064)
			(stroke
				(width 0.1524)
				(type default)
			)
			(layer "B.SilkS")
		)
		(fp_line
			(start -0.7874 -0.4064)
			(end -0.7874 0.4064)
			(stroke
				(width 0.1524)
				(type default)
			)
			(layer "B.SilkS")
		)
		(fp_line
			(start 0.7874 0.4064)
			(end 0.7874 -0.4064)
			(stroke
				(width 0.1524)
				(type default)
			)
			(layer "B.SilkS")
		)
		(fp_line
			(start -0.7874 0.4064)
			(end 0.7874 0.4064)
			(stroke
				(width 0.1524)
				(type default)
			)
			(layer "B.SilkS")
		)
		(fp_line
			(start 0.67945 -0.305054)
			(end 0.12065 -0.305054)
			(stroke
				(width 0.1)
				(type default)
			)
			(layer "B.Fab")
		)
		(fp_line
			(start 0.12065 -0.305054)
			(end 0.12065 -0.2794)
			(stroke
				(width 0.1)
				(type default)
			)
			(layer "B.Fab")
		)
		(fp_line
			(start -0.12065 -0.3048)
			(end -0.67945 -0.3048)
			(stroke
				(width 0.1)
				(type default)
			)
			(layer "B.Fab")
		)
		(fp_line
			(start -0.67945 -0.3048)
			(end -0.67945 0.3048)
			(stroke
				(width 0.1)
				(type default)
			)
			(layer "B.Fab")
		)
		(fp_line
			(start 0.12065 -0.2794)
			(end -0.12065 -0.2794)
			(stroke
				(width 0.1)
				(type default)
			)
			(layer "B.Fab")
		)
		(fp_line
			(start -0.12065 -0.2794)
			(end -0.12065 -0.3048)
			(stroke
				(width 0.1)
				(type default)
			)
			(layer "B.Fab")
		)
		(fp_line
			(start 0.12065 0.2794)
			(end 0.12065 0.3048)
			(stroke
				(width 0.1)
				(type default)
			)
			(layer "B.Fab")
		)
		(fp_line
			(start -0.120396 0.2794)
			(end 0.12065 0.2794)
			(stroke
				(width 0.1)
				(type default)
			)
			(layer "B.Fab")
		)
		(fp_line
			(start 0.67945 0.3048)
			(end 0.67945 -0.305054)
			(stroke
				(width 0.1)
				(type default)
			)
			(layer "B.Fab")
		)
		(fp_line
			(start 0.12065 0.3048)
			(end 0.67945 0.3048)
			(stroke
				(width 0.1)
				(type default)
			)
			(layer "B.Fab")
		)
		(fp_line
			(start -0.120396 0.3048)
			(end -0.120396 0.2794)
			(stroke
				(width 0.1)
				(type default)
			)
			(layer "B.Fab")
		)
		(fp_line
			(start -0.67945 0.3048)
			(end -0.120396 0.3048)
			(stroke
				(width 0.1)
				(type default)
			)
			(layer "B.Fab")
		)
		(pad "1" smd circle
			(at 0.40005 0 270)
			(size 0 0)
			(layers "B.Cu" "B.Mask" "B.Paste")
			(net "PWRGD_CHH_CPU1_DIMM1")
		)
		(pad "2" smd circle
			(at -0.40005 0 270)
			(size 0 0)
			(layers "B.Cu" "B.Mask" "B.Paste")
			(net "PWRGD_FAIL_CPU1_GH")
		)
	)
	(footprint ""
		(layer "B.Cu")
		(at 332.7781 -33.173416 90)
		(property "Reference" "R501"
			(at 0 0 90)
			(layer "B.SilkS")
			(hide yes)
			(effects
				(font
					(size 1.27 1.27)
				)
				(justify mirror)
			)
		)
		(property "Value" ""
			(at 0 0 90)
			(layer "B.Fab")
			(effects
				(font
					(size 1.27 1.27)
				)
				(justify mirror)
			)
		)
		(duplicate_pad_numbers_are_jumpers no)
		(fp_line
			(start 0.7874 -0.4064)
			(end -0.7874 -0.4064)
			(stroke
				(width 0.1524)
				(type default)
			)
			(layer "B.SilkS")
		)
		(fp_line
			(start -0.7874 -0.4064)
			(end -0.7874 0.4064)
			(stroke
				(width 0.1524)
				(type default)
			)
			(layer "B.SilkS")
		)
		(fp_line
			(start 0.7874 0.4064)
			(end 0.7874 -0.4064)
			(stroke
				(width 0.1524)
				(type default)
			)
			(layer "B.SilkS")
		)
		(fp_line
			(start -0.7874 0.4064)
			(end 0.7874 0.4064)
			(stroke
				(width 0.1524)
				(type default)
			)
			(layer "B.SilkS")
		)
		(fp_line
			(start 0.67945 -0.305054)
			(end 0.12065 -0.305054)
			(stroke
				(width 0.1)
				(type default)
			)
			(layer "B.Fab")
		)
		(fp_line
			(start 0.12065 -0.305054)
			(end 0.12065 -0.2794)
			(stroke
				(width 0.1)
				(type default)
			)
			(layer "B.Fab")
		)
		(fp_line
			(start -0.12065 -0.3048)
			(end -0.67945 -0.3048)
			(stroke
				(width 0.1)
				(type default)
			)
			(layer "B.Fab")
		)
		(fp_line
			(start -0.67945 -0.3048)
			(end -0.67945 0.3048)
			(stroke
				(width 0.1)
				(type default)
			)
			(layer "B.Fab")
		)
		(fp_line
			(start 0.12065 -0.2794)
			(end -0.12065 -0.2794)
			(stroke
				(width 0.1)
				(type default)
			)
			(layer "B.Fab")
		)
		(fp_line
			(start -0.12065 -0.2794)
			(end -0.12065 -0.3048)
			(stroke
				(width 0.1)
				(type default)
			)
			(layer "B.Fab")
		)
		(fp_line
			(start 0.12065 0.2794)
			(end 0.12065 0.3048)
			(stroke
				(width 0.1)
				(type default)
			)
			(layer "B.Fab")
		)
		(fp_line
			(start -0.120396 0.2794)
			(end 0.12065 0.2794)
			(stroke
				(width 0.1)
				(type default)
			)
			(layer "B.Fab")
		)
		(fp_line
			(start 0.67945 0.3048)
			(end 0.67945 -0.305054)
			(stroke
				(width 0.1)
				(type default)
			)
			(layer "B.Fab")
		)
		(fp_line
			(start 0.12065 0.3048)
			(end 0.67945 0.3048)
			(stroke
				(width 0.1)
				(type default)
			)
			(layer "B.Fab")
		)
		(fp_line
			(start -0.120396 0.3048)
			(end -0.120396 0.2794)
			(stroke
				(width 0.1)
				(type default)
			)
			(layer "B.Fab")
		)
		(fp_line
			(start -0.67945 0.3048)
			(end -0.120396 0.3048)
			(stroke
				(width 0.1)
				(type default)
			)
			(layer "B.Fab")
		)
		(pad "1" smd circle
			(at 0.40005 0 270)
			(size 0 0)
			(layers "B.Cu" "B.Mask" "B.Paste")
			(net "SPI_PCH_CS0_R_N")
		)
		(pad "2" smd circle
			(at -0.40005 0 270)
			(size 0 0)
			(layers "B.Cu" "B.Mask" "B.Paste")
			(net "SPI_SYS_CS0_N")
		)
	)
)
